# S9S_MB_2U (Grand Teton) — schematic netlist excerpt (pin names and nets, part order shuffled) for the footprints in the layout excerpt that follows; sources: Cadence DE-HDL packaged netlist, KiCad conversion of 03242023_DA0F0TMBIJ0_F0T_Motherboard_J_brd_V01_OCP.brd

R143  Q_RES  49.9 1% CHIP  pkg 0402LF  page 197 : A = PECI_PCH ; B = PECI_PCH_R
R3241  Q_RES  2.2K 5% EMPTY  pkg 0402LF  page 241 : A = SMB_OCP_SFF_3V3AUX_SDA ; B = P3V3_AUX

(kicad_pcb
	(version 20260206)
	(generator "pcbnew")
	(generator_version "10.0")
	(general
		(thickness 1.6)
		(legacy_teardrops no)
	)
	(paper "A4")
	(title_block
		(title "03242023_DA0F0TMBIJ0_F0T_Motherboard_J_brd_V01_OCP.brd")
		(comment 1 "Grand Teton / footprints 2843-2844 of 6105")
	)
	(layers
		(0 "F.Cu" signal "TOP")
		(4 "In1.Cu" signal "GND")
		(6 "In2.Cu" signal "IN1")
		(8 "In3.Cu" signal "GND1")
		(10 "In4.Cu" signal "IN2")
		(12 "In5.Cu" signal "GND2")
		(14 "In6.Cu" signal "IN3")
		(16 "In7.Cu" signal "GND3")
		(18 "In8.Cu" signal "VCC")
		(20 "In9.Cu" signal "VCC1")
		(22 "In10.Cu" signal "GND4")
		(24 "In11.Cu" signal "IN4")
		(26 "In12.Cu" signal "GND5")
		(28 "In13.Cu" signal "IN5")
		(30 "In14.Cu" signal "GND6")
		(32 "In15.Cu" signal "IN6")
		(34 "In16.Cu" signal "GND7")
		(2 "B.Cu" signal "BOTTOM")
		(9 "F.Adhes" user "F.Adhesive")
		(11 "B.Adhes" user "B.Adhesive")
		(13 "F.Paste" user "Package Geometry/Pastemask Top")
		(15 "B.Paste" user "Package Geometry/Pastemask Bottom")
		(5 "F.SilkS" user "Ref Des/Silkscreen Top")
		(7 "B.SilkS" user "Ref Des/Silkscreen Bottom")
		(1 "F.Mask" user "Board Geometry/Soldermask Top")
		(3 "B.Mask" user "Board Geometry/Soldermask Bottom")
		(17 "Dwgs.User" user "User.Drawings")
		(19 "Cmts.User" user "User.Comments")
		(21 "Eco1.User" user "User.Eco1")
		(23 "Eco2.User" user "User.Eco2")
		(25 "Edge.Cuts" user "Board Geometry/Outline")
		(27 "Margin" user)
		(31 "F.CrtYd" user "Package Geometry/Place Bound Top")
		(29 "B.CrtYd" user "Package Geometry/Place Bound Bottom")
		(35 "F.Fab" user "Ref Des/Assembly Top")
		(33 "B.Fab" user "Ref Des/Assembly Bottom")
	)
	(footprint ""
		(layer "F.Cu")
		(at 308.79288 -53.050948 90)
		(property "Reference" "R143"
			(at 0 0 90)
			(layer "F.SilkS")
			(hide yes)
			(effects
				(font
					(size 1.27 1.27)
				)
			)
		)
		(property "Value" ""
			(at 0 0 90)
			(layer "F.Fab")
			(effects
				(font
					(size 1.27 1.27)
				)
			)
		)
		(duplicate_pad_numbers_are_jumpers no)
		(fp_line
			(start 0.7874 -0.4064)
			(end 0.7874 0.4064)
			(stroke
				(width 0.1524)
				(type default)
			)
			(layer "F.SilkS")
		)
		(fp_line
			(start -0.7874 -0.4064)
			(end 0.7874 -0.4064)
			(stroke
				(width 0.1524)
				(type default)
			)
			(layer "F.SilkS")
		)
		(fp_line
			(start 0.7874 0.4064)
			(end -0.7874 0.4064)
			(stroke
				(width 0.1524)
				(type default)
			)
			(layer "F.SilkS")
		)
		(fp_line
			(start -0.7874 0.4064)
			(end -0.7874 -0.4064)
			(stroke
				(width 0.1524)
				(type default)
			)
			(layer "F.SilkS")
		)
		(fp_line
			(start -0.12065 -0.305054)
			(end -0.12065 -0.2794)
			(stroke
				(width 0.1)
				(type default)
			)
			(layer "F.Fab")
		)
		(fp_line
			(start -0.67945 -0.305054)
			(end -0.12065 -0.305054)
			(stroke
				(width 0.1)
				(type default)
			)
			(layer "F.Fab")
		)
		(fp_line
			(start 0.67945 -0.3048)
			(end 0.67945 0.3048)
			(stroke
				(width 0.1)
				(type default)
			)
			(layer "F.Fab")
		)
		(fp_line
			(start 0.12065 -0.3048)
			(end 0.67945 -0.3048)
			(stroke
				(width 0.1)
				(type default)
			)
			(layer "F.Fab")
		)
		(fp_line
			(start 0.12065 -0.2794)
			(end 0.12065 -0.3048)
			(stroke
				(width 0.1)
				(type default)
			)
			(layer "F.Fab")
		)
		(fp_line
			(start -0.12065 -0.2794)
			(end 0.12065 -0.2794)
			(stroke
				(width 0.1)
				(type default)
			)
			(layer "F.Fab")
		)
		(fp_line
			(start 0.120396 0.2794)
			(end -0.12065 0.2794)
			(stroke
				(width 0.1)
				(type default)
			)
			(layer "F.Fab")
		)
		(fp_line
			(start -0.12065 0.2794)
			(end -0.12065 0.3048)
			(stroke
				(width 0.1)
				(type default)
			)
			(layer "F.Fab")
		)
		(fp_line
			(start 0.67945 0.3048)
			(end 0.120396 0.3048)
			(stroke
				(width 0.1)
				(type default)
			)
			(layer "F.Fab")
		)
		(fp_line
			(start 0.120396 0.3048)
			(end 0.120396 0.2794)
			(stroke
				(width 0.1)
				(type default)
			)
			(layer "F.Fab")
		)
		(fp_line
			(start -0.12065 0.3048)
			(end -0.67945 0.3048)
			(stroke
				(width 0.1)
				(type default)
			)
			(layer "F.Fab")
		)
		(fp_line
			(start -0.67945 0.3048)
			(end -0.67945 -0.305054)
			(stroke
				(width 0.1)
				(type default)
			)
			(layer "F.Fab")
		)
		(pad "1" smd circle
			(at -0.40005 0 90)
			(size 0 0)
			(layers "F.Cu" "F.Mask" "F.Paste")
			(net "PECI_PCH")
		)
		(pad "2" smd circle
			(at 0.40005 0 90)
			(size 0 0)
			(layers "F.Cu" "F.Mask" "F.Paste")
			(net "PECI_PCH_R")
		)
	)
	(footprint ""
		(layer "F.Cu")
		(at 438.87771 -43.960288 180)
		(property "Reference" "R3241"
			(at 0 0 180)
			(layer "F.SilkS")
			(hide yes)
			(effects
				(font
					(size 1.27 1.27)
				)
			)
		)
		(property "Value" ""
			(at 0 0 180)
			(layer "F.Fab")
			(effects
				(font
					(size 1.27 1.27)
				)
			)
		)
		(duplicate_pad_numbers_are_jumpers no)
		(fp_line
			(start 0.7874 0.4064)
			(end -0.7874 0.4064)
			(stroke
				(width 0.1524)
				(type default)
			)
			(layer "F.SilkS")
		)
		(fp_line
			(start 0.7874 -0.4064)
			(end 0.7874 0.4064)
			(stroke
				(width 0.1524)
				(type default)
			)
			(layer "F.SilkS")
		)
		(fp_line
			(start -0.7874 0.4064)
			(end -0.7874 -0.4064)
			(stroke
				(width 0.1524)
				(type default)
			)
			(layer "F.SilkS")
		)
		(fp_line
			(start -0.7874 -0.4064)
			(end 0.7874 -0.4064)
			(stroke
				(width 0.1524)
				(type default)
			)
			(layer "F.SilkS")
		)
		(fp_line
			(start 0.67945 0.3048)
			(end 0.120396 0.3048)
			(stroke
				(width 0.1)
				(type default)
			)
			(layer "F.Fab")
		)
		(fp_line
			(start 0.67945 -0.3048)
			(end 0.67945 0.3048)
			(stroke
				(width 0.1)
				(type default)
			)
			(layer "F.Fab")
		)
		(fp_line
			(start 0.12065 -0.2794)
			(end 0.12065 -0.3048)
			(stroke
				(width 0.1)
				(type default)
			)
			(layer "F.Fab")
		)
		(fp_line
			(start 0.12065 -0.3048)
			(end 0.67945 -0.3048)
			(stroke
				(width 0.1)
				(type default)
			)
			(layer "F.Fab")
		)
		(fp_line
			(start 0.120396 0.3048)
			(end 0.120396 0.2794)
			(stroke
				(width 0.1)
				(type default)
			)
			(layer "F.Fab")
		)
		(fp_line
			(start 0.120396 0.2794)
			(end -0.12065 0.2794)
			(stroke
				(width 0.1)
				(type default)
			)
			(layer "F.Fab")
		)
		(fp_line
			(start -0.12065 0.3048)
			(end -0.67945 0.3048)
			(stroke
				(width 0.1)
				(type default)
			)
			(layer "F.Fab")
		)
		(fp_line
			(start -0.12065 0.2794)
			(end -0.12065 0.3048)
			(stroke
				(width 0.1)
				(type default)
			)
			(layer "F.Fab")
		)
		(fp_line
			(start -0.12065 -0.2794)
			(end 0.12065 -0.2794)
			(stroke
				(width 0.1)
				(type default)
			)
			(layer "F.Fab")
		)
		(fp_line
			(start -0.12065 -0.305054)
			(end -0.12065 -0.2794)
			(stroke
				(width 0.1)
				(type default)
			)
			(layer "F.Fab")
		)
		(fp_line
			(start -0.67945 0.3048)
			(end -0.67945 -0.305054)
			(stroke
				(width 0.1)
				(type default)
			)
			(layer "F.Fab")
		)
		(fp_line
			(start -0.67945 -0.305054)
			(end -0.12065 -0.305054)
			(stroke
				(width 0.1)
				(type default)
			)
			(layer "F.Fab")
		)
		(pad "1" smd circle
			(at -0.40005 0 180)
			(size 0 0)
			(layers "F.Cu" "F.Mask" "F.Paste")
			(net "SMB_OCP_SFF_3V3AUX_SDA")
		)
		(pad "2" smd circle
			(at 0.40005 0 180)
			(size 0 0)
			(layers "F.Cu" "F.Mask" "F.Paste")
			(net "P3V3_AUX")
		)
	)
)
